# TIMECARD (Time Appliance Project (Time Card)) — schematic netlist excerpt (pin names and nets, part order shuffled) for the footprints in the layout excerpt that follows; sources: Cadence DE-HDL packaged netlist, KiCad conversion of R4006-B0001-02_R01.brd

R249  RESISTOR  4.7KOHM 1%  pkg SMC_0402R_H016  page 29 : \1\ = XP1R0V_COMP ; \2\ = UNNAMED_523_CAPACITOR_I9_1
R260  RESISTOR  1KOHM 1%  pkg SMC_0402R_H016  page 31 : \1\ = XP3R3V ; \2\ = XP3R3V_FPGA_EN_R

(kicad_pcb
	(version 20260206)
	(generator "pcbnew")
	(generator_version "10.0")
	(general
		(thickness 1.6)
		(legacy_teardrops no)
	)
	(paper "A4")
	(title_block
		(title "timecard-production-celestica-r4006 — R4006-B0001-02_R01.brd")
		(comment 1 "Time Appliance Project (Time Card) / footprints 948-949 of 1113")
	)
	(layers
		(0 "F.Cu" signal "TOP")
		(4 "In1.Cu" signal "L02_GND1")
		(6 "In2.Cu" signal "L03_SIG1")
		(8 "In3.Cu" signal "L04_GND2")
		(10 "In4.Cu" signal "L05_VCC1")
		(12 "In5.Cu" signal "L06_VCC2")
		(14 "In6.Cu" signal "L07_GND3")
		(16 "In7.Cu" signal "L08_SIG2")
		(18 "In8.Cu" signal "L09_GND4")
		(2 "B.Cu" signal "BOTTOM")
		(9 "F.Adhes" user "F.Adhesive")
		(11 "B.Adhes" user "B.Adhesive")
		(13 "F.Paste" user "Package Geometry/Pastemask Top")
		(15 "B.Paste" user "Package Geometry/Pastemask Bottom")
		(5 "F.SilkS" user "Ref Des/Silkscreen Top")
		(7 "B.SilkS" user "Ref Des/Silkscreen Bottom")
		(1 "F.Mask" user "Board Geometry/Soldermask Top")
		(3 "B.Mask" user "Board Geometry/Soldermask Bottom")
		(17 "Dwgs.User" user "User.Drawings")
		(19 "Cmts.User" user "User.Comments")
		(21 "Eco1.User" user "User.Eco1")
		(23 "Eco2.User" user "User.Eco2")
		(25 "Edge.Cuts" user "Board Geometry/Outline")
		(27 "Margin" user)
		(31 "F.CrtYd" user "Package Geometry/Place Bound Top")
		(29 "B.CrtYd" user "Package Geometry/Place Bound Bottom")
		(35 "F.Fab" user "Ref Des/Assembly Top")
		(33 "B.Fab" user "Ref Des/Assembly Bottom")
	)
	(footprint ""
		(layer "B.Cu")
		(at 115.443 -70.993)
		(property "Reference" "R260"
			(at -0.127 2.19837 0)
			(unlocked yes)
			(layer "B.SilkS")
			(effects
				(font
					(size 0.7874 0.5842)
					(thickness 0.1524)
				)
				(justify mirror)
			)
		)
		(property "Value" "VAL*"
			(at -0.02032 2.13233 0)
			(unlocked yes)
			(layer "B.Fab")
			(hide yes)
			(effects
				(font
					(size 0.7874 0.5842)
					(thickness 0.1524)
				)
				(justify mirror)
			)
		)
		(property "Tolerance" "TOL*"
			(at -0.044704 3.05435 0)
			(unlocked yes)
			(layer "Cmts.User")
			(hide yes)
			(effects
				(font
					(size 0.7874 0.5842)
					(thickness 0.1524)
				)
				(justify mirror)
			)
		)
		(property "User Part Number" "PARTNUM*"
			(at -0.02032 4.024884 0)
			(unlocked yes)
			(layer "Cmts.User")
			(hide yes)
			(effects
				(font
					(size 0.7874 0.5842)
					(thickness 0.1524)
				)
				(justify mirror)
			)
		)
		(property "Device Type" "RESISTOR-G155-11001-01,1KOHM,1%"
			(at -0.008382 1.210564 0)
			(unlocked yes)
			(layer "B.Fab")
			(hide yes)
			(effects
				(font
					(size 0.7874 0.5842)
					(thickness 0.1524)
				)
				(justify mirror)
			)
		)
		(duplicate_pad_numbers_are_jumpers no)
		(fp_line
			(start -1.143 -0.5588)
			(end 1.143 -0.5588)
			(stroke
				(width 0.1)
				(type default)
			)
			(layer "B.SilkS")
		)
		(fp_line
			(start -1.143 0.5588)
			(end -1.143 -0.5588)
			(stroke
				(width 0.1)
				(type default)
			)
			(layer "B.SilkS")
		)
		(fp_line
			(start 1.143 -0.5588)
			(end 1.143 0.5588)
			(stroke
				(width 0.1)
				(type default)
			)
			(layer "B.SilkS")
		)
		(fp_line
			(start 1.143 0.5588)
			(end -1.143 0.5588)
			(stroke
				(width 0.1)
				(type default)
			)
			(layer "B.SilkS")
		)
		(fp_rect
			(start -1.143 0.5588)
			(end 1.143 -0.5588)
			(stroke
				(width 0)
				(type default)
			)
			(fill no)
			(layer "B.CrtYd")
		)
		(fp_line
			(start -0.508 -0.3048)
			(end 0.508 -0.3048)
			(stroke
				(width 0.1)
				(type default)
			)
			(layer "B.Fab")
		)
		(fp_line
			(start -0.508 0.3048)
			(end -0.508 -0.3048)
			(stroke
				(width 0.1)
				(type default)
			)
			(layer "B.Fab")
		)
		(fp_line
			(start 0.508 -0.3048)
			(end 0.508 0.3048)
			(stroke
				(width 0.1)
				(type default)
			)
			(layer "B.Fab")
		)
		(fp_line
			(start 0.508 0.3048)
			(end -0.508 0.3048)
			(stroke
				(width 0.1)
				(type default)
			)
			(layer "B.Fab")
		)
		(pad "1" smd rect
			(at 0.5334 0 180)
			(size 0.7112 0.6096)
			(layers "B.Cu" "B.Mask" "B.Paste")
			(net "XP3R3V")
		)
		(pad "2" smd rect
			(at -0.5334 0 180)
			(size 0.7112 0.6096)
			(layers "B.Cu" "B.Mask" "B.Paste")
			(net "XP3R3V_FPGA_EN_R")
		)
		(zone
			(layer "B.Cu")
			(hatch none 0.5)
			(connect_pads
				(clearance 0)
			)
			(min_thickness 0.25)
			(keepout
				(tracks allowed)
				(vias not_allowed)
				(pads allowed)
				(copperpour not_allowed)
				(footprints allowed)
			)
			(placement
				(enabled no)
				(sheetname "")
			)
			(fill
				(thermal_gap 0.5)
				(thermal_bridge_width 0.5)
				(island_removal_mode 0)
			)
			(polygon
				(pts
					(xy 115.3668 -70.6882) (xy 115.5192 -70.6882) (xy 115.5192 -71.2978) (xy 115.3668 -71.2978)
				)
			)
		)
	)
	(footprint ""
		(layer "B.Cu")
		(at 142.24 -59.563 -90)
		(property "Reference" "R249"
			(at -3.175 0.16637 270)
			(unlocked yes)
			(layer "B.SilkS")
			(effects
				(font
					(size 0.7874 0.5842)
					(thickness 0.1524)
				)
				(justify mirror)
			)
		)
		(property "Value" "VAL*"
			(at -0.02032 2.13233 270)
			(unlocked yes)
			(layer "B.Fab")
			(hide yes)
			(effects
				(font
					(size 0.7874 0.5842)
					(thickness 0.1524)
				)
				(justify mirror)
			)
		)
		(property "Device Type" "RESISTOR-G155-14701-01,4.7KOHMA"
			(at -0.008382 1.210564 270)
			(unlocked yes)
			(layer "B.Fab")
			(hide yes)
			(effects
				(font
					(size 0.7874 0.5842)
					(thickness 0.1524)
				)
				(justify mirror)
			)
		)
		(property "User Part Number" "PARTNUM*"
			(at -0.02032 4.024884 270)
			(unlocked yes)
			(layer "Cmts.User")
			(hide yes)
			(effects
				(font
					(size 0.7874 0.5842)
					(thickness 0.1524)
				)
				(justify mirror)
			)
		)
		(property "Tolerance" "TOL*"
			(at -0.044704 3.05435 270)
			(unlocked yes)
			(layer "Cmts.User")
			(hide yes)
			(effects
				(font
					(size 0.7874 0.5842)
					(thickness 0.1524)
				)
				(justify mirror)
			)
		)
		(duplicate_pad_numbers_are_jumpers no)
		(fp_line
			(start -1.143 0.5588)
			(end -1.143 -0.5588)
			(stroke
				(width 0.1)
				(type default)
			)
			(layer "B.SilkS")
		)
		(fp_line
			(start 1.143 0.5588)
			(end -1.143 0.5588)
			(stroke
				(width 0.1)
				(type default)
			)
			(layer "B.SilkS")
		)
		(fp_line
			(start -1.143 -0.5588)
			(end 1.143 -0.5588)
			(stroke
				(width 0.1)
				(type default)
			)
			(layer "B.SilkS")
		)
		(fp_line
			(start 1.143 -0.5588)
			(end 1.143 0.5588)
			(stroke
				(width 0.1)
				(type default)
			)
			(layer "B.SilkS")
		)
		(fp_rect
			(start 1.143 0.5588)
			(end -1.143 -0.5588)
			(stroke
				(width 0)
				(type default)
			)
			(fill no)
			(layer "B.CrtYd")
		)
		(fp_line
			(start -0.508 0.3048)
			(end -0.508 -0.3048)
			(stroke
				(width 0.1)
				(type default)
			)
			(layer "B.Fab")
		)
		(fp_line
			(start 0.508 0.3048)
			(end -0.508 0.3048)
			(stroke
				(width 0.1)
				(type default)
			)
			(layer "B.Fab")
		)
		(fp_line
			(start -0.508 -0.3048)
			(end 0.508 -0.3048)
			(stroke
				(width 0.1)
				(type default)
			)
			(layer "B.Fab")
		)
		(fp_line
			(start 0.508 -0.3048)
			(end 0.508 0.3048)
			(stroke
				(width 0.1)
				(type default)
			)
			(layer "B.Fab")
		)
		(pad "1" smd rect
			(at 0.5334 0 90)
			(size 0.7112 0.6096)
			(layers "B.Cu" "B.Mask" "B.Paste")
			(net "XP1R0V_COMP")
		)
		(pad "2" smd rect
			(at -0.5334 0 90)
			(size 0.7112 0.6096)
			(layers "B.Cu" "B.Mask" "B.Paste")
			(net "UNNAMED_523_CAPACITOR_I9_1")
		)
		(zone
			(layer "B.Cu")
			(hatch none 0.5)
			(connect_pads
				(clearance 0)
			)
			(min_thickness 0.25)
			(keepout
				(tracks allowed)
				(vias not_allowed)
				(pads allowed)
				(copperpour not_allowed)
				(footprints allowed)
			)
			(placement
				(enabled no)
				(sheetname "")
			)
			(fill
				(thermal_gap 0.5)
				(thermal_bridge_width 0.5)
				(island_removal_mode 0)
			)
			(polygon
				(pts
					(xy 141.9352 -59.4868) (xy 142.5448 -59.4868) (xy 142.5448 -59.6392) (xy 141.9352 -59.6392)
				)
			)
		)
	)
)
